# T6G (Grand Teton) — schematic netlist excerpt (pin names and nets, part order shuffled) for the footprints in the layout excerpt that follows; sources: Cadence DE-HDL packaged netlist, KiCad conversion of 04192023_DAF0TMB3IC0_F0TG_MB_C_brd_V02_OCP.brd

PC2208  Q_CAP  1UF 25V 10% X6S  pkg C0402  page 146 : A = P3V3_AUX ; B = GND
R1389  Q_RES  10K 1% CHIP  pkg 0201LF  page 320 : A = RXDET_BYP_RT_CPU1_P0 ; B = GND
PR288  Q_RES  49.9 1% CHIP  pkg 0402LF  page 224 : A = VSENSE_VSS_SENSE_C_P1 ; B = GND

(kicad_pcb
	(version 20260206)
	(generator "pcbnew")
	(generator_version "10.0")
	(general
		(thickness 1.6)
		(legacy_teardrops no)
	)
	(paper "A4")
	(title_block
		(title "04192023_DAF0TMB3IC0_F0TG_MB_C_brd_V02_OCP.brd")
		(comment 1 "Grand Teton / footprints 1814-1816 of 8354")
	)
	(layers
		(0 "F.Cu" signal "TOP")
		(4 "In1.Cu" signal "GND")
		(6 "In2.Cu" signal "IN1")
		(8 "In3.Cu" signal "GND1")
		(10 "In4.Cu" signal "IN2")
		(12 "In5.Cu" signal "GND2")
		(14 "In6.Cu" signal "IN3")
		(16 "In7.Cu" signal "GND3")
		(18 "In8.Cu" signal "VCC")
		(20 "In9.Cu" signal "VCC1")
		(22 "In10.Cu" signal "GND4")
		(24 "In11.Cu" signal "IN4")
		(26 "In12.Cu" signal "GND5")
		(28 "In13.Cu" signal "IN5")
		(30 "In14.Cu" signal "GND6")
		(32 "In15.Cu" signal "IN6")
		(34 "In16.Cu" signal "GND7")
		(2 "B.Cu" signal "BOTTOM")
		(9 "F.Adhes" user "F.Adhesive")
		(11 "B.Adhes" user "B.Adhesive")
		(13 "F.Paste" user "Package Geometry/Pastemask Top")
		(15 "B.Paste" user "Package Geometry/Pastemask Bottom")
		(5 "F.SilkS" user "Ref Des/Silkscreen Top")
		(7 "B.SilkS" user "Ref Des/Silkscreen Bottom")
		(1 "F.Mask" user "Board Geometry/Soldermask Top")
		(3 "B.Mask" user "Board Geometry/Soldermask Bottom")
		(17 "Dwgs.User" user "User.Drawings")
		(19 "Cmts.User" user "User.Comments")
		(21 "Eco1.User" user "User.Eco1")
		(23 "Eco2.User" user "User.Eco2")
		(25 "Edge.Cuts" user "Board Geometry/Outline")
		(27 "Margin" user)
		(31 "F.CrtYd" user "Package Geometry/Place Bound Top")
		(29 "B.CrtYd" user "Package Geometry/Place Bound Bottom")
		(35 "F.Fab" user "Ref Des/Assembly Top")
		(33 "B.Fab" user "Ref Des/Assembly Bottom")
	)
	(footprint ""
		(layer "F.Cu")
		(at 170.8404 -332.232508)
		(property "Reference" "PR288"
			(at 0 0 0)
			(layer "F.SilkS")
			(hide yes)
			(effects
				(font
					(size 1.27 1.27)
				)
			)
		)
		(property "Value" ""
			(at 0 0 0)
			(layer "F.Fab")
			(effects
				(font
					(size 1.27 1.27)
				)
			)
		)
		(duplicate_pad_numbers_are_jumpers no)
		(fp_line
			(start -0.7874 -0.4064)
			(end 0.7874 -0.4064)
			(stroke
				(width 0.1524)
				(type default)
			)
			(layer "F.SilkS")
		)
		(fp_line
			(start -0.7874 0.4064)
			(end -0.7874 -0.4064)
			(stroke
				(width 0.1524)
				(type default)
			)
			(layer "F.SilkS")
		)
		(fp_line
			(start 0.7874 -0.4064)
			(end 0.7874 0.4064)
			(stroke
				(width 0.1524)
				(type default)
			)
			(layer "F.SilkS")
		)
		(fp_line
			(start 0.7874 0.4064)
			(end -0.7874 0.4064)
			(stroke
				(width 0.1524)
				(type default)
			)
			(layer "F.SilkS")
		)
		(fp_line
			(start -0.67945 -0.305054)
			(end -0.12065 -0.305054)
			(stroke
				(width 0.1)
				(type default)
			)
			(layer "F.Fab")
		)
		(fp_line
			(start -0.67945 0.3048)
			(end -0.67945 -0.305054)
			(stroke
				(width 0.1)
				(type default)
			)
			(layer "F.Fab")
		)
		(fp_line
			(start -0.12065 -0.305054)
			(end -0.12065 -0.2794)
			(stroke
				(width 0.1)
				(type default)
			)
			(layer "F.Fab")
		)
		(fp_line
			(start -0.12065 -0.2794)
			(end 0.12065 -0.2794)
			(stroke
				(width 0.1)
				(type default)
			)
			(layer "F.Fab")
		)
		(fp_line
			(start -0.12065 0.2794)
			(end -0.12065 0.3048)
			(stroke
				(width 0.1)
				(type default)
			)
			(layer "F.Fab")
		)
		(fp_line
			(start -0.12065 0.3048)
			(end -0.67945 0.3048)
			(stroke
				(width 0.1)
				(type default)
			)
			(layer "F.Fab")
		)
		(fp_line
			(start 0.120396 0.2794)
			(end -0.12065 0.2794)
			(stroke
				(width 0.1)
				(type default)
			)
			(layer "F.Fab")
		)
		(fp_line
			(start 0.120396 0.3048)
			(end 0.120396 0.2794)
			(stroke
				(width 0.1)
				(type default)
			)
			(layer "F.Fab")
		)
		(fp_line
			(start 0.12065 -0.3048)
			(end 0.67945 -0.3048)
			(stroke
				(width 0.1)
				(type default)
			)
			(layer "F.Fab")
		)
		(fp_line
			(start 0.12065 -0.2794)
			(end 0.12065 -0.3048)
			(stroke
				(width 0.1)
				(type default)
			)
			(layer "F.Fab")
		)
		(fp_line
			(start 0.67945 -0.3048)
			(end 0.67945 0.3048)
			(stroke
				(width 0.1)
				(type default)
			)
			(layer "F.Fab")
		)
		(fp_line
			(start 0.67945 0.3048)
			(end 0.120396 0.3048)
			(stroke
				(width 0.1)
				(type default)
			)
			(layer "F.Fab")
		)
		(pad "1" smd circle
			(at -0.40005 0)
			(size 0 0)
			(layers "F.Cu" "F.Mask" "F.Paste")
			(net "VSENSE_VSS_SENSE_C_P1")
		)
		(pad "2" smd circle
			(at 0.40005 0)
			(size 0 0)
			(layers "F.Cu" "F.Mask" "F.Paste")
			(net "GND")
		)
	)
	(footprint ""
		(layer "F.Cu")
		(at 69.6976 -389.95858)
		(property "Reference" "R1389"
			(at 0 0 0)
			(layer "F.SilkS")
			(hide yes)
			(effects
				(font
					(size 1.27 1.27)
				)
			)
		)
		(property "Value" ""
			(at 0 0 0)
			(layer "F.Fab")
			(effects
				(font
					(size 1.27 1.27)
				)
			)
		)
		(duplicate_pad_numbers_are_jumpers no)
		(fp_line
			(start -0.32512 -0.175006)
			(end 0.32512 -0.175006)
			(stroke
				(width 0.1)
				(type default)
			)
			(layer "F.Fab")
		)
		(fp_line
			(start -0.32512 0.175006)
			(end -0.32512 -0.175006)
			(stroke
				(width 0.1)
				(type default)
			)
			(layer "F.Fab")
		)
		(fp_line
			(start 0.32512 -0.175006)
			(end 0.32512 0.175006)
			(stroke
				(width 0.1)
				(type default)
			)
			(layer "F.Fab")
		)
		(fp_line
			(start 0.32512 0.175006)
			(end -0.32512 0.175006)
			(stroke
				(width 0.1)
				(type default)
			)
			(layer "F.Fab")
		)
		(pad "1" smd rect
			(at -0.2667 0)
			(size 0.3048 0.381)
			(layers "F.Cu" "F.Mask" "F.Paste")
			(net "RXDET_BYP_RT_CPU1_P0")
		)
		(pad "2" smd rect
			(at 0.2667 0 180)
			(size 0.3048 0.381)
			(layers "F.Cu" "F.Mask" "F.Paste")
			(net "GND")
		)
	)
	(footprint ""
		(layer "F.Cu")
		(at 219.347034 -75.02779 -90)
		(property "Reference" "PC2208"
			(at 0 0 270)
			(layer "F.SilkS")
			(hide yes)
			(effects
				(font
					(size 1.27 1.27)
				)
			)
		)
		(property "Value" ""
			(at 0 0 270)
			(layer "F.Fab")
			(effects
				(font
					(size 1.27 1.27)
				)
			)
		)
		(duplicate_pad_numbers_are_jumpers no)
		(fp_line
			(start -0.7874 0.4064)
			(end -0.7874 -0.4064)
			(stroke
				(width 0.1524)
				(type default)
			)
			(layer "F.SilkS")
		)
		(fp_line
			(start 0.7874 0.4064)
			(end -0.7874 0.4064)
			(stroke
				(width 0.1524)
				(type default)
			)
			(layer "F.SilkS")
		)
		(fp_line
			(start -0.7874 -0.4064)
			(end 0.7874 -0.4064)
			(stroke
				(width 0.1524)
				(type default)
			)
			(layer "F.SilkS")
		)
		(fp_line
			(start 0.7874 -0.4064)
			(end 0.7874 0.4064)
			(stroke
				(width 0.1524)
				(type default)
			)
			(layer "F.SilkS")
		)
		(fp_line
			(start -0.67945 0.3048)
			(end -0.67945 -0.305054)
			(stroke
				(width 0.1)
				(type default)
			)
			(layer "F.Fab")
		)
		(fp_line
			(start -0.12065 0.3048)
			(end -0.67945 0.3048)
			(stroke
				(width 0.1)
				(type default)
			)
			(layer "F.Fab")
		)
		(fp_line
			(start 0.120396 0.3048)
			(end 0.120396 0.2794)
			(stroke
				(width 0.1)
				(type default)
			)
			(layer "F.Fab")
		)
		(fp_line
			(start 0.67945 0.3048)
			(end 0.120396 0.3048)
			(stroke
				(width 0.1)
				(type default)
			)
			(layer "F.Fab")
		)
		(fp_line
			(start -0.12065 0.2794)
			(end -0.12065 0.3048)
			(stroke
				(width 0.1)
				(type default)
			)
			(layer "F.Fab")
		)
		(fp_line
			(start 0.120396 0.2794)
			(end -0.12065 0.2794)
			(stroke
				(width 0.1)
				(type default)
			)
			(layer "F.Fab")
		)
		(fp_line
			(start -0.12065 -0.2794)
			(end 0.12065 -0.2794)
			(stroke
				(width 0.1)
				(type default)
			)
			(layer "F.Fab")
		)
		(fp_line
			(start 0.12065 -0.2794)
			(end 0.12065 -0.3048)
			(stroke
				(width 0.1)
				(type default)
			)
			(layer "F.Fab")
		)
		(fp_line
			(start 0.12065 -0.3048)
			(end 0.67945 -0.3048)
			(stroke
				(width 0.1)
				(type default)
			)
			(layer "F.Fab")
		)
		(fp_line
			(start 0.67945 -0.3048)
			(end 0.67945 0.3048)
			(stroke
				(width 0.1)
				(type default)
			)
			(layer "F.Fab")
		)
		(fp_line
			(start -0.67945 -0.305054)
			(end -0.12065 -0.305054)
			(stroke
				(width 0.1)
				(type default)
			)
			(layer "F.Fab")
		)
		(fp_line
			(start -0.12065 -0.305054)
			(end -0.12065 -0.2794)
			(stroke
				(width 0.1)
				(type default)
			)
			(layer "F.Fab")
		)
		(pad "1" smd circle
			(at -0.40005 0 270)
			(size 0 0)
			(layers "F.Cu" "F.Mask" "F.Paste")
			(net "P3V3_AUX")
		)
		(pad "2" smd circle
			(at 0.40005 0 270)
			(size 0 0)
			(layers "F.Cu" "F.Mask" "F.Paste")
			(net "GND")
		)
	)
)
